# SCM (Grand Teton) — schematic netlist excerpt (pin names and nets, part order shuffled) for the footprints in the layout excerpt that follows; sources: Cadence DE-HDL packaged netlist, KiCad conversion of 12092022_DA0F0TMDCD0_F0T_Management_Board_D_brd_V3_OCP.brd

C207  Q_CAP  15PF 50V 5% C0G  pkg 0402  page 23 : A = V_DACB ; B = GND
R254  Q_RES  10K 1% CHIP  pkg 0402LF  page 27 : A = P3V3_AUX ; B = SMB_BMC_MM6_SCL

(kicad_pcb
	(version 20260206)
	(generator "pcbnew")
	(generator_version "10.0")
	(general
		(thickness 1.6)
		(legacy_teardrops no)
	)
	(paper "A4")
	(title_block
		(title "12092022_DA0F0TMDCD0_F0T_Management_Board_D_brd_V3_OCP.brd")
		(comment 1 "Grand Teton / footprints 1179-1180 of 1440")
	)
	(layers
		(0 "F.Cu" signal "TOP")
		(4 "In1.Cu" signal "GND")
		(6 "In2.Cu" signal "IN1")
		(8 "In3.Cu" signal "GND1")
		(10 "In4.Cu" signal "IN2")
		(12 "In5.Cu" signal "VCC")
		(14 "In6.Cu" signal "VCC1")
		(16 "In7.Cu" signal "IN3")
		(18 "In8.Cu" signal "GND2")
		(20 "In9.Cu" signal "IN4")
		(22 "In10.Cu" signal "GND3")
		(2 "B.Cu" signal "BOTTOM")
		(9 "F.Adhes" user "F.Adhesive")
		(11 "B.Adhes" user "B.Adhesive")
		(13 "F.Paste" user "Package Geometry/Pastemask Top")
		(15 "B.Paste" user "Package Geometry/Pastemask Bottom")
		(5 "F.SilkS" user "Ref Des/Silkscreen Top")
		(7 "B.SilkS" user "Ref Des/Silkscreen Bottom")
		(1 "F.Mask" user "Board Geometry/Soldermask Top")
		(3 "B.Mask" user "Board Geometry/Soldermask Bottom")
		(17 "Dwgs.User" user "User.Drawings")
		(19 "Cmts.User" user "User.Comments")
		(21 "Eco1.User" user "User.Eco1")
		(23 "Eco2.User" user "User.Eco2")
		(25 "Edge.Cuts" user "Board Geometry/Outline")
		(27 "Margin" user)
		(31 "F.CrtYd" user "Package Geometry/Place Bound Top")
		(29 "B.CrtYd" user "Package Geometry/Place Bound Bottom")
		(35 "F.Fab" user "Ref Des/Assembly Top")
		(33 "B.Fab" user "Ref Des/Assembly Bottom")
	)
	(footprint ""
		(layer "B.Cu")
		(at 58.77941 -30.867604 -90)
		(property "Reference" "R254"
			(at 0 0 90)
			(layer "B.SilkS")
			(hide yes)
			(effects
				(font
					(size 1.27 1.27)
				)
				(justify mirror)
			)
		)
		(property "Value" ""
			(at 0 0 90)
			(layer "B.Fab")
			(effects
				(font
					(size 1.27 1.27)
				)
				(justify mirror)
			)
		)
		(duplicate_pad_numbers_are_jumpers no)
		(fp_line
			(start -0.7874 0.4064)
			(end 0.7874 0.4064)
			(stroke
				(width 0.1524)
				(type default)
			)
			(layer "B.SilkS")
		)
		(fp_line
			(start 0.7874 0.4064)
			(end 0.7874 -0.4064)
			(stroke
				(width 0.1524)
				(type default)
			)
			(layer "B.SilkS")
		)
		(fp_line
			(start -0.7874 -0.4064)
			(end -0.7874 0.4064)
			(stroke
				(width 0.1524)
				(type default)
			)
			(layer "B.SilkS")
		)
		(fp_line
			(start 0.7874 -0.4064)
			(end -0.7874 -0.4064)
			(stroke
				(width 0.1524)
				(type default)
			)
			(layer "B.SilkS")
		)
		(fp_line
			(start -0.67945 0.3048)
			(end -0.120396 0.3048)
			(stroke
				(width 0.1)
				(type default)
			)
			(layer "B.Fab")
		)
		(fp_line
			(start -0.120396 0.3048)
			(end -0.120396 0.2794)
			(stroke
				(width 0.1)
				(type default)
			)
			(layer "B.Fab")
		)
		(fp_line
			(start 0.12065 0.3048)
			(end 0.67945 0.3048)
			(stroke
				(width 0.1)
				(type default)
			)
			(layer "B.Fab")
		)
		(fp_line
			(start 0.67945 0.3048)
			(end 0.67945 -0.305054)
			(stroke
				(width 0.1)
				(type default)
			)
			(layer "B.Fab")
		)
		(fp_line
			(start -0.120396 0.2794)
			(end 0.12065 0.2794)
			(stroke
				(width 0.1)
				(type default)
			)
			(layer "B.Fab")
		)
		(fp_line
			(start 0.12065 0.2794)
			(end 0.12065 0.3048)
			(stroke
				(width 0.1)
				(type default)
			)
			(layer "B.Fab")
		)
		(fp_line
			(start -0.12065 -0.2794)
			(end -0.12065 -0.3048)
			(stroke
				(width 0.1)
				(type default)
			)
			(layer "B.Fab")
		)
		(fp_line
			(start 0.12065 -0.2794)
			(end -0.12065 -0.2794)
			(stroke
				(width 0.1)
				(type default)
			)
			(layer "B.Fab")
		)
		(fp_line
			(start -0.67945 -0.3048)
			(end -0.67945 0.3048)
			(stroke
				(width 0.1)
				(type default)
			)
			(layer "B.Fab")
		)
		(fp_line
			(start -0.12065 -0.3048)
			(end -0.67945 -0.3048)
			(stroke
				(width 0.1)
				(type default)
			)
			(layer "B.Fab")
		)
		(fp_line
			(start 0.12065 -0.305054)
			(end 0.12065 -0.2794)
			(stroke
				(width 0.1)
				(type default)
			)
			(layer "B.Fab")
		)
		(fp_line
			(start 0.67945 -0.305054)
			(end 0.12065 -0.305054)
			(stroke
				(width 0.1)
				(type default)
			)
			(layer "B.Fab")
		)
		(pad "1" smd circle
			(at 0.40005 0 90)
			(size 0 0)
			(layers "B.Cu" "B.Mask" "B.Paste")
			(net "P3V3_AUX")
		)
		(pad "2" smd circle
			(at -0.40005 0 90)
			(size 0 0)
			(layers "B.Cu" "B.Mask" "B.Paste")
			(net "SMB_BMC_MM6_SCL")
		)
	)
	(footprint ""
		(layer "B.Cu")
		(at 29.3624 -30.35935 -90)
		(property "Reference" "C207"
			(at 0 0 90)
			(layer "B.SilkS")
			(hide yes)
			(effects
				(font
					(size 1.27 1.27)
				)
				(justify mirror)
			)
		)
		(property "Value" ""
			(at 0 0 90)
			(layer "B.Fab")
			(effects
				(font
					(size 1.27 1.27)
				)
				(justify mirror)
			)
		)
		(duplicate_pad_numbers_are_jumpers no)
		(fp_line
			(start -0.7874 0.4064)
			(end 0.7874 0.4064)
			(stroke
				(width 0.1524)
				(type default)
			)
			(layer "B.SilkS")
		)
		(fp_line
			(start 0.7874 0.4064)
			(end 0.7874 -0.4064)
			(stroke
				(width 0.1524)
				(type default)
			)
			(layer "B.SilkS")
		)
		(fp_line
			(start -0.7874 -0.4064)
			(end -0.7874 0.4064)
			(stroke
				(width 0.1524)
				(type default)
			)
			(layer "B.SilkS")
		)
		(fp_line
			(start 0.7874 -0.4064)
			(end -0.7874 -0.4064)
			(stroke
				(width 0.1524)
				(type default)
			)
			(layer "B.SilkS")
		)
		(fp_line
			(start -0.67945 0.3048)
			(end -0.120396 0.3048)
			(stroke
				(width 0.1)
				(type default)
			)
			(layer "B.Fab")
		)
		(fp_line
			(start -0.120396 0.3048)
			(end -0.120396 0.2794)
			(stroke
				(width 0.1)
				(type default)
			)
			(layer "B.Fab")
		)
		(fp_line
			(start 0.12065 0.3048)
			(end 0.67945 0.3048)
			(stroke
				(width 0.1)
				(type default)
			)
			(layer "B.Fab")
		)
		(fp_line
			(start 0.67945 0.3048)
			(end 0.67945 -0.305054)
			(stroke
				(width 0.1)
				(type default)
			)
			(layer "B.Fab")
		)
		(fp_line
			(start -0.120396 0.2794)
			(end 0.12065 0.2794)
			(stroke
				(width 0.1)
				(type default)
			)
			(layer "B.Fab")
		)
		(fp_line
			(start 0.12065 0.2794)
			(end 0.12065 0.3048)
			(stroke
				(width 0.1)
				(type default)
			)
			(layer "B.Fab")
		)
		(fp_line
			(start -0.12065 -0.2794)
			(end -0.12065 -0.3048)
			(stroke
				(width 0.1)
				(type default)
			)
			(layer "B.Fab")
		)
		(fp_line
			(start 0.12065 -0.2794)
			(end -0.12065 -0.2794)
			(stroke
				(width 0.1)
				(type default)
			)
			(layer "B.Fab")
		)
		(fp_line
			(start -0.67945 -0.3048)
			(end -0.67945 0.3048)
			(stroke
				(width 0.1)
				(type default)
			)
			(layer "B.Fab")
		)
		(fp_line
			(start -0.12065 -0.3048)
			(end -0.67945 -0.3048)
			(stroke
				(width 0.1)
				(type default)
			)
			(layer "B.Fab")
		)
		(fp_line
			(start 0.12065 -0.305054)
			(end 0.12065 -0.2794)
			(stroke
				(width 0.1)
				(type default)
			)
			(layer "B.Fab")
		)
		(fp_line
			(start 0.67945 -0.305054)
			(end 0.12065 -0.305054)
			(stroke
				(width 0.1)
				(type default)
			)
			(layer "B.Fab")
		)
		(pad "1" smd circle
			(at 0.40005 0 90)
			(size 0 0)
			(layers "B.Cu" "B.Mask" "B.Paste")
			(net "V_DACB")
		)
		(pad "2" smd circle
			(at -0.40005 0 90)
			(size 0 0)
			(layers "B.Cu" "B.Mask" "B.Paste")
			(net "GND")
		)
	)
)
